(kicad_pcb
	(version 20241229)
	(generator "pcbnew")
	(generator_version "9.0")
	(general
		(thickness 1.61)
		(legacy_teardrops no)
	)
	(paper "A3")
	(title_block
		(title "RDIMM DDR5 Tester")
		(date "2026-05-21")
		(rev "2.2.0")
		(company "Antmicro")
		(comment 9 "footprints 170-173 of 796")
	)
	(layers
		(0 "F.Cu" signal)
		(4 "In1.Cu" power)
		(6 "In2.Cu" mixed)
		(8 "In3.Cu" power)
		(10 "In4.Cu" mixed)
		(12 "In5.Cu" power)
		(14 "In6.Cu" mixed)
		(16 "In7.Cu" power)
		(18 "In8.Cu" power)
		(20 "In9.Cu" mixed)
		(22 "In10.Cu" power)
		(2 "B.Cu" signal)
		(9 "F.Adhes" user "F.Adhesive")
		(11 "B.Adhes" user "B.Adhesive")
		(13 "F.Paste" user)
		(15 "B.Paste" user)
		(5 "F.SilkS" user "F.Silkscreen")
		(7 "B.SilkS" user "B.Silkscreen")
		(1 "F.Mask" user)
		(3 "B.Mask" user)
		(17 "Dwgs.User" user "User.Drawings")
		(19 "Cmts.User" user "User.Comments")
		(21 "Eco1.User" user "User.Eco1")
		(23 "Eco2.User" user "User.Eco2")
		(25 "Edge.Cuts" user)
		(27 "Margin" user)
		(31 "F.CrtYd" user "F.Courtyard")
		(29 "B.CrtYd" user "B.Courtyard")
		(35 "F.Fab" user)
		(33 "B.Fab" user)
	)
	(footprint "antmicro-footprints:L_0402_1005Metric"
		(layer "F.Cu")
		(at 121.025 154.61 180)
		(descr "Inductor SMD 0402")
		(tags "Inductor SMD 0402")
		(property "Reference" "L7"
			(at -5.425 -0.415 0)
			(layer "F.SilkS")
			(effects
				(font
					(size 0.7 0.7)
					(thickness 0.15)
				)
				(justify right bottom)
			)
		)
		(property "Value" "L_20n_0.35A_0402"
			(at 0 1.4 0)
			(layer "F.Fab")
			(effects
				(font
					(size 0.7 0.7)
					(thickness 0.15)
				)
				(justify right bottom)
			)
		)
		(property "Datasheet" "https://product.tdk.com/system/files/dam/doc/product/inductor/inductor/smd/catalog/inductor_automotive_high-frequency_mlg1005s_en.pdf?ref_disty=mouser"
			(at 0 0 180)
			(layer "F.Fab")
			(hide yes)
			(effects
				(font
					(size 1.27 1.27)
					(thickness 0.15)
				)
			)
		)
		(property "Val" "20n/0.35A"
			(at 0 0 180)
			(unlocked yes)
			(layer "F.Fab")
			(hide yes)
			(effects
				(font
					(size 1 1)
					(thickness 0.15)
				)
			)
		)
		(property "Manufacturer" "TDK"
			(at 0 0 180)
			(unlocked yes)
			(layer "F.Fab")
			(hide yes)
			(effects
				(font
					(size 1 1)
					(thickness 0.15)
				)
			)
		)
		(property "MPN" "MLG1005S20NJTD25"
			(at 0 0 180)
			(unlocked yes)
			(layer "F.Fab")
			(hide yes)
			(effects
				(font
					(size 1 1)
					(thickness 0.15)
				)
			)
		)
		(property "ISat" ""
			(at 0 0 180)
			(unlocked yes)
			(layer "F.Fab")
			(hide yes)
			(effects
				(font
					(size 1 1)
					(thickness 0.15)
				)
			)
		)
		(property "IMax" "0.35 A"
			(at 0 0 180)
			(unlocked yes)
			(layer "F.Fab")
			(hide yes)
			(effects
				(font
					(size 1 1)
					(thickness 0.15)
				)
			)
		)
		(property "Size" "1.0x0.5"
			(at 0 0 180)
			(unlocked yes)
			(layer "F.Fab")
			(hide yes)
			(effects
				(font
					(size 1 1)
					(thickness 0.15)
				)
			)
		)
		(property "Author" "Antmicro"
			(at 0 0 180)
			(unlocked yes)
			(layer "F.Fab")
			(hide yes)
			(effects
				(font
					(size 1 1)
					(thickness 0.15)
				)
			)
		)
		(property "License" "Apache-2.0"
			(at 0 0 180)
			(unlocked yes)
			(layer "F.Fab")
			(hide yes)
			(effects
				(font
					(size 1 1)
					(thickness 0.15)
				)
			)
		)
		(sheetname "/HDMI + SD Card/")
		(sheetfile "hdmi-sd-card.kicad_sch")
		(attr smd)
		(fp_rect
			(start -0.925 -0.47)
			(end 0.925 0.47)
			(stroke
				(width 0.05)
				(type default)
			)
			(fill no)
			(layer "F.CrtYd")
		)
		(fp_rect
			(start -0.499 -0.249)
			(end 0.499 0.249)
			(stroke
				(width 0.15)
				(type solid)
			)
			(fill no)
			(layer "F.Fab")
		)
		(fp_text user "${REFERENCE}"
			(at -0.932 3.168 180)
			(layer "F.Fab")
			(effects
				(font
					(size 0.7 0.7)
					(thickness 0.15)
				)
				(justify left bottom)
			)
		)
		(fp_text user "License: Apache-2.0"
			(at -0.932 5.17 180)
			(layer "F.Fab")
			(effects
				(font
					(size 0.7 0.7)
					(thickness 0.15)
				)
				(justify left bottom)
			)
		)
		(fp_text user "Author: Antmicro"
			(at -0.932 4.17 180)
			(layer "F.Fab")
			(effects
				(font
					(size 0.7 0.7)
					(thickness 0.15)
				)
				(justify left bottom)
			)
		)
		(pad "1" smd roundrect
			(at -0.48 0 180)
			(size 0.59 0.64)
			(layers "F.Cu" "F.Mask" "F.Paste")
			(roundrect_rratio 0.25)
			(net 292 "/FPGA MGT Interface/HDMI_IN.CLK_N")
			(pintype "passive")
		)
		(pad "2" smd roundrect
			(at 0.48 0 180)
			(size 0.59 0.64)
			(layers "F.Cu" "F.Mask" "F.Paste")
			(roundrect_rratio 0.25)
			(net 677 "Net-(L7-Pad2)")
			(pintype "passive")
		)
	)
	(footprint "antmicro-footprints:Oscillator_SMD_Epson_SG3225EEN_3.2x2.5x1.2mm"
		(layer "F.Cu")
		(at 169.385 158.45 90)
		(property "Reference" "Y3"
			(at -2.77 0.535 0)
			(unlocked yes)
			(layer "F.SilkS")
			(effects
				(font
					(size 0.7 0.7)
					(thickness 0.15)
				)
				(justify left bottom)
			)
		)
		(property "Value" "Oscillator_100MHz_SG3225VAN"
			(at 0 3 90)
			(unlocked yes)
			(layer "F.Fab")
			(effects
				(font
					(size 0.7 0.7)
					(thickness 0.15)
				)
				(justify left bottom)
			)
		)
		(property "Datasheet" "https://support.epson.biz/td/api/doc_check.php?dl=brief_SG5032VAN&lang=en"
			(at 0 0 90)
			(layer "F.Fab")
			(hide yes)
			(effects
				(font
					(size 1.27 1.27)
					(thickness 0.15)
				)
			)
		)
		(property "Manufacturer" "Epson"
			(at 0 0 90)
			(unlocked yes)
			(layer "F.Fab")
			(hide yes)
			(effects
				(font
					(size 1 1)
					(thickness 0.15)
				)
			)
		)
		(property "MPN" "SG3225VAN_100.000000M-KEGA3"
			(at 0 0 90)
			(unlocked yes)
			(layer "F.Fab")
			(hide yes)
			(effects
				(font
					(size 1 1)
					(thickness 0.15)
				)
			)
		)
		(property "Val" "100MHz"
			(at 0 0 90)
			(unlocked yes)
			(layer "F.Fab")
			(hide yes)
			(effects
				(font
					(size 1 1)
					(thickness 0.15)
				)
			)
		)
		(property "Author" "Antmicro"
			(at 0 0 90)
			(unlocked yes)
			(layer "F.Fab")
			(hide yes)
			(effects
				(font
					(size 1 1)
					(thickness 0.15)
				)
			)
		)
		(property "License" "Apache-2.0"
			(at 0 0 90)
			(unlocked yes)
			(layer "F.Fab")
			(hide yes)
			(effects
				(font
					(size 1 1)
					(thickness 0.15)
				)
			)
		)
		(sheetname "/FPGA banks HP/")
		(sheetfile "fpga-hp-banks.kicad_sch")
		(attr smd)
		(fp_line
			(start 1.25 -1.825)
			(end -1.25 -1.825)
			(stroke
				(width 0.15)
				(type solid)
			)
			(layer "F.SilkS")
		)
		(fp_line
			(start 1.25 1.925)
			(end -1.25 1.925)
			(stroke
				(width 0.15)
				(type solid)
			)
			(layer "F.SilkS")
		)
		(fp_circle
			(center -1.57 -1.87)
			(end -1.57 -1.82)
			(stroke
				(width 0.15)
				(type solid)
			)
			(fill yes)
			(layer "F.SilkS")
		)
		(fp_rect
			(start 1.58 -1.85)
			(end -1.6 1.96)
			(stroke
				(width 0.05)
				(type solid)
			)
			(fill no)
			(layer "F.CrtYd")
		)
		(fp_text user "${REFERENCE}"
			(at -2.29 5.11 90)
			(unlocked yes)
			(layer "F.Fab")
			(effects
				(font
					(size 0.7 0.7)
					(thickness 0.15)
				)
				(justify left bottom)
			)
		)
		(fp_text user "License: Apache-2.0"
			(at -2.29 3.91 90)
			(layer "F.Fab")
			(effects
				(font
					(size 0.7 0.7)
					(thickness 0.15)
				)
				(justify left bottom)
			)
		)
		(fp_text user "Author: Antmicro"
			(at -2.29 6.31 90)
			(layer "F.Fab")
			(effects
				(font
					(size 0.7 0.7)
					(thickness 0.15)
				)
				(justify left bottom)
			)
		)
		(pad "1" smd rect
			(at -0.925 -1.24)
			(size 0.92 1.05)
			(layers "F.Cu" "F.Mask" "F.Paste")
			(net 151 "+3V3")
			(pinfunction "EN")
			(pintype "input")
			(solder_mask_margin 0.05)
		)
		(pad "2" smd rect
			(at -0.925 0.05)
			(size 0.8 1.05)
			(layers "F.Cu" "F.Mask" "F.Paste")
			(net 645 "unconnected-(Y3-NC-Pad2)")
			(pinfunction "NC")
			(pintype "no_connect")
			(solder_mask_margin 0.05)
		)
		(pad "3" smd rect
			(at -0.925 1.34)
			(size 0.92 1.05)
			(layers "F.Cu" "F.Mask" "F.Paste")
			(net 1 "GND")
			(pinfunction "GND")
			(pintype "power_in")
			(solder_mask_margin 0.05)
		)
		(pad "4" smd rect
			(at 0.925 1.34)
			(size 0.92 1.05)
			(layers "F.Cu" "F.Mask" "F.Paste")
			(net 543 "/FPGA banks HP/GCLK_100_LVDS+")
			(pinfunction "OUT+")
			(pintype "output")
			(solder_mask_margin 0.05)
		)
		(pad "5" smd rect
			(at 0.925 0.05)
			(size 0.8 1.05)
			(layers "F.Cu" "F.Mask" "F.Paste")
			(net 544 "/FPGA banks HP/GCLK_100_LVDS-")
			(pinfunction "OUT-")
			(pintype "output")
			(solder_mask_margin 0.05)
		)
		(pad "6" smd rect
			(at 0.925 -1.24)
			(size 0.92 1.05)
			(layers "F.Cu" "F.Mask" "F.Paste")
			(net 151 "+3V3")
			(pinfunction "VCC")
			(pintype "power_in")
			(solder_mask_margin 0.05)
		)
	)
	(footprint "antmicro-footprints:C_0402_1005Metric"
		(layer "F.Cu")
		(at 122.076 176.032 90)
		(descr "Capacitor SMD 0402")
		(tags "capacitor SMD 0402")
		(property "Reference" "C280"
			(at 1.21 0.41 90)
			(layer "F.SilkS")
			(effects
				(font
					(size 0.7 0.7)
					(thickness 0.15)
				)
				(justify left bottom)
			)
		)
		(property "Value" "C_100n_0402"
			(at -1.022927 2.155213 90)
			(layer "F.Fab")
			(effects
				(font
					(size 0.7 0.7)
					(thickness 0.15)
				)
				(justify left bottom)
			)
		)
		(property "Datasheet" "https://www.murata.com/products/productdetail?partno=GRM155R61H104KE14%23"
			(at 0 0 90)
			(layer "F.Fab")
			(hide yes)
			(effects
				(font
					(size 1.27 1.27)
					(thickness 0.15)
				)
			)
		)
		(property "MPN" "GRM155R61H104KE14D"
			(at 0 0 90)
			(unlocked yes)
			(layer "F.Fab")
			(hide yes)
			(effects
				(font
					(size 1 1)
					(thickness 0.15)
				)
			)
		)
		(property "Manufacturer" "Murata"
			(at 0 0 90)
			(unlocked yes)
			(layer "F.Fab")
			(hide yes)
			(effects
				(font
					(size 1 1)
					(thickness 0.15)
				)
			)
		)
		(property "License" "Apache-2.0"
			(at 0 0 90)
			(unlocked yes)
			(layer "F.Fab")
			(hide yes)
			(effects
				(font
					(size 1 1)
					(thickness 0.15)
				)
			)
		)
		(property "Author" "Antmicro"
			(at 0 0 90)
			(unlocked yes)
			(layer "F.Fab")
			(hide yes)
			(effects
				(font
					(size 1 1)
					(thickness 0.15)
				)
			)
		)
		(property "Val" "100n"
			(at 0 0 90)
			(unlocked yes)
			(layer "F.Fab")
			(hide yes)
			(effects
				(font
					(size 1 1)
					(thickness 0.15)
				)
			)
		)
		(property "Voltage" "50V"
			(at 0 0 90)
			(unlocked yes)
			(layer "F.Fab")
			(hide yes)
			(effects
				(font
					(size 1 1)
					(thickness 0.15)
				)
			)
		)
		(property "Dielectric" "X5R"
			(at 0 0 90)
			(unlocked yes)
			(layer "F.Fab")
			(hide yes)
			(effects
				(font
					(size 1 1)
					(thickness 0.15)
				)
			)
		)
		(property "Public" ""
			(at 0 0 90)
			(unlocked yes)
			(layer "F.Fab")
			(hide yes)
			(effects
				(font
					(size 1 1)
					(thickness 0.15)
				)
			)
		)
		(sheetname "/HDMI + SD Card/")
		(sheetfile "hdmi-sd-card.kicad_sch")
		(attr smd)
		(fp_rect
			(start -0.925 -0.47)
			(end 0.925 0.47)
			(stroke
				(width 0.05)
				(type default)
			)
			(fill no)
			(layer "F.CrtYd")
		)
		(fp_line
			(start 0.504 -0.25)
			(end 0.504 0.248)
			(stroke
				(width 0.15)
				(type solid)
			)
			(layer "F.Fab")
		)
		(fp_line
			(start -0.494 -0.25)
			(end 0.504 -0.25)
			(stroke
				(width 0.15)
				(type solid)
			)
			(layer "F.Fab")
		)
		(fp_line
			(start 0.504 0.248)
			(end -0.494 0.248)
			(stroke
				(width 0.15)
				(type solid)
			)
			(layer "F.Fab")
		)
		(fp_line
			(start -0.494 0.248)
			(end -0.494 -0.25)
			(stroke
				(width 0.15)
				(type solid)
			)
			(layer "F.Fab")
		)
		(fp_text user "Author: Antmicro"
			(at -0.939 3.399 90)
			(layer "F.Fab")
			(effects
				(font
					(size 0.7 0.7)
					(thickness 0.15)
				)
				(justify left bottom)
			)
		)
		(fp_text user "${REFERENCE}"
			(at -0.939 4.599 90)
			(layer "F.Fab")
			(effects
				(font
					(size 0.7 0.7)
					(thickness 0.15)
				)
				(justify left bottom)
			)
		)
		(fp_text user "License: Apache-2.0"
			(at -0.939 5.799 90)
			(layer "F.Fab")
			(effects
				(font
					(size 0.7 0.7)
					(thickness 0.15)
				)
				(justify left bottom)
			)
		)
		(pad "1" smd roundrect
			(at -0.48 0 90)
			(size 0.59 0.64)
			(layers "F.Cu" "F.Mask" "F.Paste")
			(roundrect_rratio 0.25)
			(net 810 "/HDMI + SD Card/HDMI_VDD")
			(pintype "passive")
		)
		(pad "2" smd roundrect
			(at 0.48 0 90)
			(size 0.59 0.64)
			(layers "F.Cu" "F.Mask" "F.Paste")
			(roundrect_rratio 0.25)
			(net 1 "GND")
			(pintype "passive")
		)
	)
	(footprint "antmicro-footprints:LED_0603_1608Metric_G"
		(layer "F.Cu")
		(at 102.605 102.225 90)
		(descr "LED SMD 0603 Green")
		(tags "LED SMD 0603 Green")
		(property "Reference" "D8"
			(at -2.575 -0.305 90)
			(layer "F.SilkS")
			(hide yes)
			(effects
				(font
					(size 0.7 0.7)
					(thickness 0.15)
				)
				(justify left bottom)
			)
		)
		(property "Value" "LED_G_0603_KP-1608CGCK"
			(at -0.001 1.599 90)
			(layer "F.Fab")
			(effects
				(font
					(size 0.7 0.7)
					(thickness 0.15)
				)
				(justify left bottom)
			)
		)
		(property "Datasheet" "http://www.kingbright.com/attachments/file/psearch//000/00/00/KP-1608CGCK(Ver.23B).pdf"
			(at 0 0 90)
			(layer "F.Fab")
			(hide yes)
			(effects
				(font
					(size 1.27 1.27)
					(thickness 0.15)
				)
			)
		)
		(property "MPN" "KP-1608CGCK"
			(at 0 0 90)
			(unlocked yes)
			(layer "F.Fab")
			(hide yes)
			(effects
				(font
					(size 1 1)
					(thickness 0.15)
				)
			)
		)
		(property "Manufacturer" "Kingbright"
			(at 0 0 90)
			(unlocked yes)
			(layer "F.Fab")
			(hide yes)
			(effects
				(font
					(size 1 1)
					(thickness 0.15)
				)
			)
		)
		(property "Author" "Antmicro"
			(at 0 0 90)
			(unlocked yes)
			(layer "F.Fab")
			(hide yes)
			(effects
				(font
					(size 1 1)
					(thickness 0.15)
				)
			)
		)
		(property "License" "Apache-2.0"
			(at 0 0 90)
			(unlocked yes)
			(layer "F.Fab")
			(hide yes)
			(effects
				(font
					(size 1 1)
					(thickness 0.15)
				)
			)
		)
		(property "Color" "Green"
			(at 0 0 90)
			(unlocked yes)
			(layer "F.Fab")
			(hide yes)
			(effects
				(font
					(size 1 1)
					(thickness 0.15)
				)
			)
		)
		(sheetname "/FPGA banks HD/")
		(sheetfile "fpga-hd-banks.kicad_sch")
		(attr smd)
		(fp_line
			(start 0.22 -0.35)
			(end -0.22 -0.35)
			(stroke
				(width 0.15)
				(type solid)
			)
			(layer "F.SilkS")
		)
		(fp_line
			(start -1.18 -0.319)
			(end -1.18 0.321)
			(stroke
				(width 0.15)
				(type solid)
			)
			(layer "F.SilkS")
		)
		(fp_line
			(start 0.105328 0.001008)
			(end 0.24 0.001)
			(stroke
				(width 0.1)
				(type solid)
			)
			(layer "F.SilkS")
		)
		(fp_line
			(start -0.094672 0.001008)
			(end 0.105328 -0.198992)
			(stroke
				(width 0.1)
				(type solid)
			)
			(layer "F.SilkS")
		)
		(fp_line
			(start -0.094672 0.001008)
			(end -0.24 0.001008)
			(stroke
				(width 0.1)
				(type solid)
			)
			(layer "F.SilkS")
		)
		(fp_line
			(start 0.105328 0.201008)
			(end 0.105328 -0.198992)
			(stroke
				(width 0.1)
				(type solid)
			)
			(layer "F.SilkS")
		)
		(fp_line
			(start 0.105328 0.201008)
			(end -0.094672 0.001008)
			(stroke
				(width 0.1)
				(type solid)
			)
			(layer "F.SilkS")
		)
		(fp_line
			(start -0.094672 0.201008)
			(end -0.094672 -0.198992)
			(stroke
				(width 0.1)
				(type solid)
			)
			(layer "F.SilkS")
		)
		(fp_line
			(start 0.22 0.35)
			(end -0.22 0.35)
			(stroke
				(width 0.15)
				(type solid)
			)
			(layer "F.SilkS")
		)
		(fp_rect
			(start 1.25 0.65)
			(end -1.25 -0.65)
			(stroke
				(width 0.05)
				(type solid)
			)
			(fill no)
			(layer "F.CrtYd")
		)
		(fp_line
			(start 0.201 -0.202)
			(end -0.101 0)
			(stroke
				(width 0.15)
				(type solid)
			)
			(layer "F.Fab")
		)
		(fp_line
			(start -0.199 -0.202)
			(end -0.199 0.1)
			(stroke
				(width 0.15)
				(type solid)
			)
			(layer "F.Fab")
		)
		(fp_line
			(start 0.599 0)
			(end 0.201 0)
			(stroke
				(width 0.15)
				(type solid)
			)
			(layer "F.Fab")
		)
		(fp_line
			(start 0.201 0)
			(end 0.201 -0.202)
			(stroke
				(width 0.15)
				(type solid)
			)
			(layer "F.Fab")
		)
		(fp_line
			(start -0.101 0)
			(end 0.201 0.2)
			(stroke
				(width 0.15)
				(type solid)
			)
			(layer "F.Fab")
		)
		(fp_line
			(start -0.199 0)
			(end -0.597 0)
			(stroke
				(width 0.15)
				(type solid)
			)
			(layer "F.Fab")
		)
		(fp_line
			(start 0.201 0.2)
			(end 0.201 0)
			(stroke
				(width 0.15)
				(type solid)
			)
			(layer "F.Fab")
		)
		(fp_line
			(start -0.199 0.2)
			(end -0.199 0.1)
			(stroke
				(width 0.15)
				(type solid)
			)
			(layer "F.Fab")
		)
		(fp_rect
			(start 0.848 0.4)
			(end -0.85 -0.402)
			(stroke
				(width 0.15)
				(type solid)
			)
			(fill no)
			(layer "F.Fab")
		)
		(fp_text user "${REFERENCE}"
			(at -1.4224 5.999 90)
			(layer "F.Fab")
			(effects
				(font
					(size 0.7 0.7)
					(thickness 0.15)
				)
				(justify left bottom)
			)
		)
		(fp_text user "Author: Antmicro"
			(at -1.4224 4.799 90)
			(layer "F.Fab")
			(effects
				(font
					(size 0.7 0.7)
					(thickness 0.15)
				)
				(justify left bottom)
			)
		)
		(fp_text user "License: Apache-2.0"
			(at -1.4224 3.599 90)
			(layer "F.Fab")
			(effects
				(font
					(size 0.7 0.7)
					(thickness 0.15)
				)
				(justify left bottom)
			)
		)
		(pad "1" smd roundrect
			(at -0.7 0 270)
			(size 0.8 1)
			(layers "F.Cu" "F.Mask" "F.Paste")
			(roundrect_rratio 0.2)
			(net 151 "+3V3")
			(pinfunction "C")
			(pintype "passive")
		)
		(pad "2" smd roundrect
			(at 0.7 0 270)
			(size 0.8 1)
			(layers "F.Cu" "F.Mask" "F.Paste")
			(roundrect_rratio 0.2)
			(net 233 "Net-(D8-A)")
			(pinfunction "A")
			(pintype "passive")
		)
	)
)
